(kicad_pcb
	(version 20260206)
	(generator "pcbnew")
	(generator_version "10.0")
	(general
		(thickness 1.6)
		(legacy_teardrops no)
	)
	(paper "A4")
	(title_block
		(title "v1-chassis-manager — T6M_CM_d_v01_1031_1645.brd")
		(comment 1 "Open CloudServer (Microsoft) / footprints 1746-1755 of 2512")
	)
	(layers
		(0 "F.Cu" signal "TOP")
		(4 "In1.Cu" signal "GND1")
		(6 "In2.Cu" signal "IN1")
		(8 "In3.Cu" signal "VCC1")
		(10 "In4.Cu" signal "VCC2")
		(12 "In5.Cu" signal "GND2")
		(14 "In6.Cu" signal "IN2")
		(16 "In7.Cu" signal "IN3")
		(18 "In8.Cu" signal "GND3")
		(2 "B.Cu" signal "BOTTOM")
		(9 "F.Adhes" user "F.Adhesive")
		(11 "B.Adhes" user "B.Adhesive")
		(13 "F.Paste" user "Package Geometry/Pastemask Top")
		(15 "B.Paste" user "Package Geometry/Pastemask Bottom")
		(5 "F.SilkS" user "Ref Des/Silkscreen Top")
		(7 "B.SilkS" user "Ref Des/Silkscreen Bottom")
		(1 "F.Mask" user "Board Geometry/Soldermask Top")
		(3 "B.Mask" user "Board Geometry/Soldermask Bottom")
		(17 "Dwgs.User" user "User.Drawings")
		(19 "Cmts.User" user "User.Comments")
		(21 "Eco1.User" user "User.Eco1")
		(23 "Eco2.User" user "User.Eco2")
		(25 "Edge.Cuts" user "Board Geometry/Outline")
		(27 "Margin" user)
		(31 "F.CrtYd" user "Package Geometry/Place Bound Top")
		(29 "B.CrtYd" user "Package Geometry/Place Bound Bottom")
		(35 "F.Fab" user "Ref Des/Assembly Top")
		(33 "B.Fab" user "Ref Des/Assembly Bottom")
	)
	(footprint ""
		(layer "B.Cu")
		(at 44.292266 -137.070338)
		(property "Reference" "C231"
			(at 1.275334 1.326388 0)
			(unlocked yes)
			(layer "B.SilkS")
			(effects
				(font
					(size 0.7874 0.5842)
					(thickness 0.1524)
				)
				(justify left mirror)
			)
		)
		(property "Value" ""
			(at 0 0 0)
			(layer "B.Fab")
			(effects
				(font
					(size 1.27 1.27)
				)
				(justify mirror)
			)
		)
		(duplicate_pad_numbers_are_jumpers no)
		(fp_line
			(start -0.7874 -0.4064)
			(end -0.7874 0.4064)
			(stroke
				(width 0.1524)
				(type default)
			)
			(layer "B.SilkS")
		)
		(fp_line
			(start -0.7874 0.4064)
			(end 0.7874 0.4064)
			(stroke
				(width 0.1524)
				(type default)
			)
			(layer "B.SilkS")
		)
		(fp_line
			(start 0 0.381)
			(end 0 -0.381)
			(stroke
				(width 0.1524)
				(type default)
			)
			(layer "B.SilkS")
		)
		(fp_line
			(start 0.7874 -0.4064)
			(end -0.7874 -0.4064)
			(stroke
				(width 0.1524)
				(type default)
			)
			(layer "B.SilkS")
		)
		(fp_line
			(start 0.7874 0.4064)
			(end 0.7874 -0.4064)
			(stroke
				(width 0.1524)
				(type default)
			)
			(layer "B.SilkS")
		)
		(fp_poly
			(pts
				(xy 0.5334 0.254) (xy 0.635 0.254) (xy 0.635 0.2286) (xy 0.635 -0.254) (xy 0.5334 -0.254) (xy 0.5334 -0.2794)
				(xy -0.5334 -0.2794) (xy -0.5334 -0.254) (xy -0.635 -0.254) (xy -0.635 0.254) (xy -0.5334 0.254)
				(xy -0.5334 0.2794) (xy 0.508 0.2794) (xy 0.5334 0.2794)
			)
			(stroke
				(width 0)
				(type default)
			)
			(fill no)
			(layer "B.CrtYd")
		)
		(pad "1" smd rect
			(at -0.40005 0 180)
			(size 0.4572 0.508)
			(layers "B.Cu" "B.Mask" "B.Paste")
			(net "P1V538_BMC_NODE1")
		)
		(pad "2" smd rect
			(at 0.40005 0 180)
			(size 0.4572 0.508)
			(layers "B.Cu" "B.Mask" "B.Paste")
			(net "GND")
		)
	)
	(footprint ""
		(layer "B.Cu")
		(at 76.448158 -151.289512 180)
		(property "Reference" "PC3"
			(at -4.631944 0.558038 0)
			(unlocked yes)
			(layer "B.SilkS")
			(effects
				(font
					(size 0.7874 0.5842)
					(thickness 0.1524)
				)
				(justify left mirror)
			)
		)
		(property "Value" ""
			(at 0 0 0)
			(layer "B.Fab")
			(effects
				(font
					(size 1.27 1.27)
				)
				(justify mirror)
			)
		)
		(duplicate_pad_numbers_are_jumpers no)
		(fp_line
			(start 2.2098 0.9398)
			(end 2.2098 -0.9398)
			(stroke
				(width 0.1524)
				(type default)
			)
			(layer "B.SilkS")
		)
		(fp_line
			(start 2.2098 -0.9398)
			(end -2.2098 -0.9398)
			(stroke
				(width 0.1524)
				(type default)
			)
			(layer "B.SilkS")
		)
		(fp_line
			(start 0 -0.9398)
			(end 0 0.9398)
			(stroke
				(width 0.1524)
				(type default)
			)
			(layer "B.SilkS")
		)
		(fp_line
			(start -2.2098 0.9398)
			(end 2.2098 0.9398)
			(stroke
				(width 0.1524)
				(type default)
			)
			(layer "B.SilkS")
		)
		(fp_line
			(start -2.2098 -0.9398)
			(end -2.2098 0.9398)
			(stroke
				(width 0.1524)
				(type default)
			)
			(layer "B.SilkS")
		)
		(fp_poly
			(pts
				(xy 1.6764 0.889) (xy 1.6764 0.7874) (xy 2.0574 0.7874) (xy 2.0574 -0.7874) (xy 1.6764 -0.7874)
				(xy 1.6764 -0.9398) (xy -1.6764 -0.9398) (xy -1.6764 -0.7874) (xy -2.0574 -0.7874) (xy -2.0574 0.7874)
				(xy -1.6764 0.7874) (xy -1.6764 0.9398) (xy 1.6764 0.9398)
			)
			(stroke
				(width 0)
				(type default)
			)
			(fill no)
			(layer "B.CrtYd")
		)
		(fp_line
			(start 1.700022 0.899922)
			(end 1.700022 -0.899922)
			(stroke
				(width 0.1)
				(type default)
			)
			(layer "B.Fab")
		)
		(fp_line
			(start 1.700022 -0.899922)
			(end -1.700022 -0.899922)
			(stroke
				(width 0.1)
				(type default)
			)
			(layer "B.Fab")
		)
		(fp_line
			(start -1.700022 0.899922)
			(end 1.700022 0.899922)
			(stroke
				(width 0.1)
				(type default)
			)
			(layer "B.Fab")
		)
		(fp_line
			(start -1.700022 -0.899922)
			(end -1.700022 0.899922)
			(stroke
				(width 0.1)
				(type default)
			)
			(layer "B.Fab")
		)
		(pad "1" smd rect
			(at -1.4732 0)
			(size 1.1684 1.5748)
			(layers "B.Cu" "B.Mask" "B.Paste")
			(net "P12V_AUX")
		)
		(pad "2" smd rect
			(at 1.4732 0)
			(size 1.1684 1.5748)
			(layers "B.Cu" "B.Mask" "B.Paste")
			(net "GND")
		)
	)
	(footprint ""
		(layer "B.Cu")
		(at 56.20004 -145.854674 180)
		(property "Reference" "R675"
			(at 0.984504 -2.813558 0)
			(unlocked yes)
			(layer "B.SilkS")
			(effects
				(font
					(size 0.7874 0.5842)
					(thickness 0.1524)
				)
				(justify left mirror)
			)
		)
		(property "Value" ""
			(at 0 0 0)
			(layer "B.Fab")
			(effects
				(font
					(size 1.27 1.27)
				)
				(justify mirror)
			)
		)
		(duplicate_pad_numbers_are_jumpers no)
		(fp_line
			(start 0.7874 0.4064)
			(end 0.7874 -0.4064)
			(stroke
				(width 0.1524)
				(type default)
			)
			(layer "B.SilkS")
		)
		(fp_line
			(start 0.7874 -0.4064)
			(end -0.7874 -0.4064)
			(stroke
				(width 0.1524)
				(type default)
			)
			(layer "B.SilkS")
		)
		(fp_line
			(start -0.7874 0.4064)
			(end 0.7874 0.4064)
			(stroke
				(width 0.1524)
				(type default)
			)
			(layer "B.SilkS")
		)
		(fp_line
			(start -0.7874 -0.4064)
			(end -0.7874 0.4064)
			(stroke
				(width 0.1524)
				(type default)
			)
			(layer "B.SilkS")
		)
		(fp_poly
			(pts
				(xy 0.508 0.2794) (xy 0.508 0.2286) (xy 0.635 0.2286) (xy 0.635 -0.254) (xy 0.5334 -0.254) (xy 0.5334 -0.2794)
				(xy -0.5334 -0.2794) (xy -0.5334 -0.254) (xy -0.635 -0.254) (xy -0.635 0.254) (xy -0.5334 0.254)
				(xy -0.5334 0.2794)
			)
			(stroke
				(width 0)
				(type default)
			)
			(fill no)
			(layer "B.CrtYd")
		)
		(pad "1" smd rect
			(at -0.40005 0)
			(size 0.4572 0.508)
			(layers "B.Cu" "B.Mask" "B.Paste")
			(net "BMC_NODE1_GFX_VSYNC_R")
		)
		(pad "2" smd rect
			(at 0.40005 0)
			(size 0.4572 0.508)
			(layers "B.Cu" "B.Mask" "B.Paste")
			(net "BMC_NODE1_GFX_VSYNC")
		)
	)
	(footprint ""
		(layer "B.Cu")
		(at 139.93876 -184.951624 90)
		(property "Reference" "R861"
			(at 4.357624 -2.004568 270)
			(unlocked yes)
			(layer "B.SilkS")
			(effects
				(font
					(size 0.7874 0.5842)
					(thickness 0.1524)
				)
				(justify left mirror)
			)
		)
		(property "Value" ""
			(at 0 0 90)
			(layer "B.Fab")
			(effects
				(font
					(size 1.27 1.27)
				)
				(justify mirror)
			)
		)
		(duplicate_pad_numbers_are_jumpers no)
		(fp_line
			(start 0.7874 -0.4064)
			(end -0.7874 -0.4064)
			(stroke
				(width 0.1524)
				(type default)
			)
			(layer "B.SilkS")
		)
		(fp_line
			(start -0.7874 -0.4064)
			(end -0.7874 0.4064)
			(stroke
				(width 0.1524)
				(type default)
			)
			(layer "B.SilkS")
		)
		(fp_line
			(start 0.7874 0.4064)
			(end 0.7874 -0.4064)
			(stroke
				(width 0.1524)
				(type default)
			)
			(layer "B.SilkS")
		)
		(fp_line
			(start -0.7874 0.4064)
			(end 0.7874 0.4064)
			(stroke
				(width 0.1524)
				(type default)
			)
			(layer "B.SilkS")
		)
		(fp_poly
			(pts
				(xy 0.508 0.2794) (xy 0.508 0.2286) (xy 0.635 0.2286) (xy 0.635 -0.254) (xy 0.5334 -0.254) (xy 0.5334 -0.2794)
				(xy -0.5334 -0.2794) (xy -0.5334 -0.254) (xy -0.635 -0.254) (xy -0.635 0.254) (xy -0.5334 0.254)
				(xy -0.5334 0.2794)
			)
			(stroke
				(width 0)
				(type default)
			)
			(fill no)
			(layer "B.CrtYd")
		)
		(pad "1" smd rect
			(at -0.40005 0 270)
			(size 0.4572 0.508)
			(layers "B.Cu" "B.Mask" "B.Paste")
			(net "T9_NODE1_EN")
		)
		(pad "2" smd rect
			(at 0.40005 0 270)
			(size 0.4572 0.508)
			(layers "B.Cu" "B.Mask" "B.Paste")
			(net "T9_NODE1_EN_R")
		)
	)
	(footprint ""
		(layer "B.Cu")
		(at 73.586848 -63.54572 -90)
		(property "Reference" "PJ11"
			(at 1.510538 -3.332734 0)
			(unlocked yes)
			(layer "B.SilkS")
			(effects
				(font
					(size 0.7874 0.5842)
					(thickness 0.1524)
				)
				(justify left mirror)
			)
		)
		(property "Value" ""
			(at 0 0 90)
			(layer "B.Fab")
			(effects
				(font
					(size 1.27 1.27)
				)
				(justify mirror)
			)
		)
		(duplicate_pad_numbers_are_jumpers no)
		(fp_poly
			(pts
				(xy -0.2794 0.907796) (xy -0.254 0.907796) (xy -0.254 1.0414) (xy 0.254 1.0414) (xy 0.254 1.034796)
				(xy 0.254 0.933196) (xy 0.2794 0.933196) (xy 0.2794 -0.133604) (xy 0.254 -0.133604) (xy 0.254 -0.235204)
				(xy -0.254 -0.235204) (xy -0.254 -0.133604) (xy -0.2794 -0.133604)
			)
			(stroke
				(width 0)
				(type default)
			)
			(fill no)
			(layer "B.CrtYd")
		)
		(pad "1" smd custom
			(at 0 -0.000254 90)
			(size 0.127 0.127)
			(layers "B.Cu" "B.Mask" "B.Paste")
			(net "VSENSE_PV_VDDR_NODE1_N")
			(options
				(clearance outline)
				(anchor circle)
			)
			(primitives
				(gr_poly
					(pts
						(xy -0.127 -0.508) (xy -0.127 0.0508) (xy -0.254 0.0508) (xy -0.254 0.508) (xy 0.254 0.508) (xy 0.254 0.0508)
						(xy 0.127 0.0508) (xy 0.127 -0.508)
					)
					(width 0)
					(fill yes)
				)
			)
		)
		(pad "2" smd rect
			(at 0 0.799846)
			(size 0.4572 0.508)
			(layers "B.Cu" "B.Mask" "B.Paste")
			(net "GND")
		)
		(zone
			(layer "B.Cu")
			(hatch none 0.5)
			(connect_pads
				(clearance 0)
			)
			(min_thickness 0.25)
			(keepout
				(tracks allowed)
				(vias not_allowed)
				(pads allowed)
				(copperpour not_allowed)
				(footprints allowed)
			)
			(placement
				(enabled no)
				(sheetname "")
			)
			(fill
				(thermal_gap 0.5)
				(thermal_bridge_width 0.5)
				(island_removal_mode 0)
			)
			(polygon
				(pts
					(xy 72.501252 -63.24092) (xy 72.501252 -63.85052) (xy 73.872852 -63.85052) (xy 73.872852 -63.24092)
				)
			)
		)
	)
	(footprint ""
		(layer "B.Cu")
		(at 160.63976 -187.872624 90)
		(property "Reference" "R829"
			(at 4.565396 -4.10083 270)
			(unlocked yes)
			(layer "B.SilkS")
			(effects
				(font
					(size 0.7874 0.5842)
					(thickness 0.1524)
				)
				(justify left mirror)
			)
		)
		(property "Value" ""
			(at 0 0 90)
			(layer "B.Fab")
			(effects
				(font
					(size 1.27 1.27)
				)
				(justify mirror)
			)
		)
		(duplicate_pad_numbers_are_jumpers no)
		(fp_line
			(start 0.7874 -0.406146)
			(end -0.7874 -0.406146)
			(stroke
				(width 0.1524)
				(type default)
			)
			(layer "B.SilkS")
		)
		(fp_line
			(start -0.7874 -0.406146)
			(end -0.7874 0.406146)
			(stroke
				(width 0.1524)
				(type default)
			)
			(layer "B.SilkS")
		)
		(fp_line
			(start 0.7874 0.406146)
			(end 0.7874 -0.406146)
			(stroke
				(width 0.1524)
				(type default)
			)
			(layer "B.SilkS")
		)
		(fp_line
			(start -0.7874 0.406146)
			(end 0.7874 0.406146)
			(stroke
				(width 0.1524)
				(type default)
			)
			(layer "B.SilkS")
		)
		(fp_poly
			(pts
				(xy 0.508 0.2794) (xy 0.508 0.2286) (xy 0.635 0.2286) (xy 0.635 -0.254) (xy 0.5334 -0.254) (xy 0.5334 -0.2794)
				(xy -0.5334 -0.2794) (xy -0.5334 -0.254) (xy -0.635 -0.254) (xy -0.635 0.254) (xy -0.5334 0.254)
				(xy -0.5334 0.2794)
			)
			(stroke
				(width 0)
				(type default)
			)
			(fill no)
			(layer "B.CrtYd")
		)
		(pad "1" smd rect
			(at -0.40005 0 270)
			(size 0.4572 0.508)
			(layers "B.Cu" "B.Mask" "B.Paste")
			(net "FAN5_TACH")
		)
		(pad "2" smd rect
			(at 0.40005 0 270)
			(size 0.4572 0.508)
			(layers "B.Cu" "B.Mask" "B.Paste")
			(net "FAN5_TACH_R")
		)
	)
	(footprint ""
		(layer "B.Cu")
		(at 144.909032 -35.662616)
		(property "Reference" "R1193"
			(at 1.24714 17.425924 0)
			(unlocked yes)
			(layer "B.SilkS")
			(effects
				(font
					(size 0.7874 0.5842)
					(thickness 0.1524)
				)
				(justify left mirror)
			)
		)
		(property "Value" ""
			(at 0 0 0)
			(layer "B.Fab")
			(effects
				(font
					(size 1.27 1.27)
				)
				(justify mirror)
			)
		)
		(duplicate_pad_numbers_are_jumpers no)
		(fp_line
			(start -0.7874 -0.4064)
			(end -0.7874 0.4064)
			(stroke
				(width 0.1524)
				(type default)
			)
			(layer "B.SilkS")
		)
		(fp_line
			(start -0.7874 0.4064)
			(end 0.7874 0.4064)
			(stroke
				(width 0.1524)
				(type default)
			)
			(layer "B.SilkS")
		)
		(fp_line
			(start 0.7874 -0.4064)
			(end -0.7874 -0.4064)
			(stroke
				(width 0.1524)
				(type default)
			)
			(layer "B.SilkS")
		)
		(fp_line
			(start 0.7874 0.4064)
			(end 0.7874 -0.4064)
			(stroke
				(width 0.1524)
				(type default)
			)
			(layer "B.SilkS")
		)
		(fp_poly
			(pts
				(xy 0.508 0.2794) (xy 0.508 0.2286) (xy 0.635 0.2286) (xy 0.635 -0.254) (xy 0.5334 -0.254) (xy 0.5334 -0.2794)
				(xy -0.5334 -0.2794) (xy -0.5334 -0.254) (xy -0.635 -0.254) (xy -0.635 0.254) (xy -0.5334 0.254)
				(xy -0.5334 0.2794)
			)
			(stroke
				(width 0)
				(type default)
			)
			(fill no)
			(layer "B.CrtYd")
		)
		(pad "1" smd rect
			(at -0.40005 0 180)
			(size 0.4572 0.508)
			(layers "B.Cu" "B.Mask" "B.Paste")
			(net "SIO_CPLD_RSV2_R")
		)
		(pad "2" smd rect
			(at 0.40005 0 180)
			(size 0.4572 0.508)
			(layers "B.Cu" "B.Mask" "B.Paste")
			(net "P3V3_NODE1")
		)
	)
	(footprint ""
		(layer "B.Cu")
		(at 45.734732 -94.40037 90)
		(property "Reference" "R132"
			(at -4.703318 -4.440174 270)
			(unlocked yes)
			(layer "B.SilkS")
			(effects
				(font
					(size 0.7874 0.5842)
					(thickness 0.1524)
				)
				(justify left mirror)
			)
		)
		(property "Value" ""
			(at 0 0 90)
			(layer "B.Fab")
			(effects
				(font
					(size 1.27 1.27)
				)
				(justify mirror)
			)
		)
		(duplicate_pad_numbers_are_jumpers no)
		(fp_line
			(start 0.7874 -0.4064)
			(end -0.7874 -0.4064)
			(stroke
				(width 0.1524)
				(type default)
			)
			(layer "B.SilkS")
		)
		(fp_line
			(start -0.7874 -0.4064)
			(end -0.7874 0.4064)
			(stroke
				(width 0.1524)
				(type default)
			)
			(layer "B.SilkS")
		)
		(fp_line
			(start 0.7874 0.4064)
			(end 0.7874 -0.4064)
			(stroke
				(width 0.1524)
				(type default)
			)
			(layer "B.SilkS")
		)
		(fp_line
			(start -0.7874 0.4064)
			(end 0.7874 0.4064)
			(stroke
				(width 0.1524)
				(type default)
			)
			(layer "B.SilkS")
		)
		(fp_poly
			(pts
				(xy 0.508 0.2794) (xy 0.508 0.2286) (xy 0.635 0.2286) (xy 0.635 -0.254) (xy 0.5334 -0.254) (xy 0.5334 -0.2794)
				(xy -0.5334 -0.2794) (xy -0.5334 -0.254) (xy -0.635 -0.254) (xy -0.635 0.254) (xy -0.5334 0.254)
				(xy -0.5334 0.2794)
			)
			(stroke
				(width 0)
				(type default)
			)
			(fill no)
			(layer "B.CrtYd")
		)
		(pad "1" smd rect
			(at -0.40005 0 270)
			(size 0.4572 0.508)
			(layers "B.Cu" "B.Mask" "B.Paste")
			(net "SMB_CPU_NODE1_BMC_DAT_RR")
		)
		(pad "2" smd rect
			(at 0.40005 0 270)
			(size 0.4572 0.508)
			(layers "B.Cu" "B.Mask" "B.Paste")
			(net "SMB_CPU_NODE1_BMC_DAT")
		)
	)
	(footprint ""
		(layer "B.Cu")
		(at 51.69408 -82.904076 90)
		(property "Reference" "R120"
			(at -32.79394 -15.07363 270)
			(unlocked yes)
			(layer "B.SilkS")
			(effects
				(font
					(size 0.7874 0.5842)
					(thickness 0.1524)
				)
				(justify left mirror)
			)
		)
		(property "Value" ""
			(at 0 0 90)
			(layer "B.Fab")
			(effects
				(font
					(size 1.27 1.27)
				)
				(justify mirror)
			)
		)
		(duplicate_pad_numbers_are_jumpers no)
		(fp_line
			(start 0.7874 -0.4064)
			(end -0.7874 -0.4064)
			(stroke
				(width 0.1524)
				(type default)
			)
			(layer "B.SilkS")
		)
		(fp_line
			(start -0.7874 -0.4064)
			(end -0.7874 0.4064)
			(stroke
				(width 0.1524)
				(type default)
			)
			(layer "B.SilkS")
		)
		(fp_line
			(start 0.7874 0.4064)
			(end 0.7874 -0.4064)
			(stroke
				(width 0.1524)
				(type default)
			)
			(layer "B.SilkS")
		)
		(fp_line
			(start -0.7874 0.4064)
			(end 0.7874 0.4064)
			(stroke
				(width 0.1524)
				(type default)
			)
			(layer "B.SilkS")
		)
		(fp_poly
			(pts
				(xy 0.508 0.2794) (xy 0.508 0.2286) (xy 0.635 0.2286) (xy 0.635 -0.254) (xy 0.5334 -0.254) (xy 0.5334 -0.2794)
				(xy -0.5334 -0.2794) (xy -0.5334 -0.254) (xy -0.635 -0.254) (xy -0.635 0.254) (xy -0.5334 0.254)
				(xy -0.5334 0.2794)
			)
			(stroke
				(width 0)
				(type default)
			)
			(fill no)
			(layer "B.CrtYd")
		)
		(pad "1" smd rect
			(at -0.40005 0 270)
			(size 0.4572 0.508)
			(layers "B.Cu" "B.Mask" "B.Paste")
			(net "A_CPU_NODE1_SOC_THERMREFNPAD")
		)
		(pad "2" smd rect
			(at 0.40005 0 270)
			(size 0.4572 0.508)
			(layers "B.Cu" "B.Mask" "B.Paste")
			(net "GND")
		)
	)
	(footprint ""
		(layer "B.Cu")
		(at 68.633086 -124.930662 -90)
		(property "Reference" "C277"
			(at 3.666744 -8.600186 270)
			(unlocked yes)
			(layer "B.SilkS")
			(effects
				(font
					(size 0.7874 0.5842)
					(thickness 0.1524)
				)
				(justify left mirror)
			)
		)
		(property "Value" ""
			(at 0 0 90)
			(layer "B.Fab")
			(effects
				(font
					(size 1.27 1.27)
				)
				(justify mirror)
			)
		)
		(duplicate_pad_numbers_are_jumpers no)
		(fp_line
			(start -0.7874 0.4064)
			(end 0.7874 0.4064)
			(stroke
				(width 0.1524)
				(type default)
			)
			(layer "B.SilkS")
		)
		(fp_line
			(start 0.7874 0.4064)
			(end 0.7874 -0.4064)
			(stroke
				(width 0.1524)
				(type default)
			)
			(layer "B.SilkS")
		)
		(fp_line
			(start 0 0.381)
			(end 0 -0.381)
			(stroke
				(width 0.1524)
				(type default)
			)
			(layer "B.SilkS")
		)
		(fp_line
			(start -0.7874 -0.4064)
			(end -0.7874 0.4064)
			(stroke
				(width 0.1524)
				(type default)
			)
			(layer "B.SilkS")
		)
		(fp_line
			(start 0.7874 -0.4064)
			(end -0.7874 -0.4064)
			(stroke
				(width 0.1524)
				(type default)
			)
			(layer "B.SilkS")
		)
		(fp_poly
			(pts
				(xy 0.5334 0.254) (xy 0.635 0.254) (xy 0.635 0.2286) (xy 0.635 -0.254) (xy 0.5334 -0.254) (xy 0.5334 -0.2794)
				(xy -0.5334 -0.2794) (xy -0.5334 -0.254) (xy -0.635 -0.254) (xy -0.635 0.254) (xy -0.5334 0.254)
				(xy -0.5334 0.2794) (xy 0.508 0.2794) (xy 0.5334 0.2794)
			)
			(stroke
				(width 0)
				(type default)
			)
			(fill no)
			(layer "B.CrtYd")
		)
		(pad "1" smd rect
			(at -0.40005 0 90)
			(size 0.4572 0.508)
			(layers "B.Cu" "B.Mask" "B.Paste")
			(net "BMC_NODE1_VCC_1V8_PCIE")
		)
		(pad "2" smd rect
			(at 0.40005 0 90)
			(size 0.4572 0.508)
			(layers "B.Cu" "B.Mask" "B.Paste")
			(net "GND")
		)
	)
)
